(kicad_pcb
	(version 20260206)
	(generator "pcbnew")
	(generator_version "10.0")
	(general
		(thickness 1.6)
		(legacy_teardrops no)
	)
	(paper "A4")
	(title_block
		(title "Wiwynn_Tioga_Pass_MB.brd")
		(comment 1 "Tioga Pass / footprints 3247-3253 of 4770")
	)
	(layers
		(0 "F.Cu" signal "TOP")
		(4 "In1.Cu" signal "L2GND")
		(6 "In2.Cu" signal "L3")
		(8 "In3.Cu" signal "L4GND")
		(10 "In4.Cu" signal "L5")
		(12 "In5.Cu" signal "L6GND")
		(14 "In6.Cu" signal "L7VCC")
		(16 "In7.Cu" signal "L8VCC")
		(18 "In8.Cu" signal "L9GND")
		(20 "In9.Cu" signal "L10")
		(22 "In10.Cu" signal "L11GND")
		(24 "In11.Cu" signal "L12")
		(26 "In12.Cu" signal "L13GND")
		(2 "B.Cu" signal "BOTTOM")
		(9 "F.Adhes" user "F.Adhesive")
		(11 "B.Adhes" user "B.Adhesive")
		(13 "F.Paste" user "Package Geometry/Pastemask Top")
		(15 "B.Paste" user "Package Geometry/Pastemask Bottom")
		(5 "F.SilkS" user "Ref Des/Silkscreen Top")
		(7 "B.SilkS" user "Ref Des/Silkscreen Bottom")
		(1 "F.Mask" user "Board Geometry/Soldermask Top")
		(3 "B.Mask" user "Board Geometry/Soldermask Bottom")
		(17 "Dwgs.User" user "User.Drawings")
		(19 "Cmts.User" user "User.Comments")
		(21 "Eco1.User" user "User.Eco1")
		(23 "Eco2.User" user "User.Eco2")
		(25 "Edge.Cuts" user "Board Geometry/Outline")
		(27 "Margin" user)
		(31 "F.CrtYd" user "Package Geometry/Place Bound Top")
		(29 "B.CrtYd" user "Package Geometry/Place Bound Bottom")
		(35 "F.Fab" user "Ref Des/Assembly Top")
		(33 "B.Fab" user "Ref Des/Assembly Bottom")
	)
	(footprint ""
		(layer "B.Cu")
		(at 13.921232 4.537456 90)
		(property "Reference" "R9U10"
			(at 0 0 90)
			(layer "B.SilkS")
			(hide yes)
			(effects
				(font
					(size 1.27 1.27)
				)
				(justify mirror)
			)
		)
		(property "Value" ""
			(at 0 0 90)
			(layer "B.Fab")
			(effects
				(font
					(size 1.27 1.27)
				)
				(justify mirror)
			)
		)
		(duplicate_pad_numbers_are_jumpers no)
		(fp_rect
			(start -0.2794 0.9906)
			(end 0.2794 -0.1016)
			(stroke
				(width 0)
				(type default)
			)
			(fill no)
			(layer "B.CrtYd")
		)
		(fp_line
			(start 0.2794 -0.1016)
			(end 0.2794 0.9906)
			(stroke
				(width 0.1)
				(type default)
			)
			(layer "B.Fab")
		)
		(fp_line
			(start -0.2794 -0.1016)
			(end 0.2794 -0.1016)
			(stroke
				(width 0.1)
				(type default)
			)
			(layer "B.Fab")
		)
		(fp_line
			(start 0.2794 0.9906)
			(end -0.2794 0.9906)
			(stroke
				(width 0.1)
				(type default)
			)
			(layer "B.Fab")
		)
		(fp_line
			(start -0.2794 0.9906)
			(end -0.2794 -0.1016)
			(stroke
				(width 0.1)
				(type default)
			)
			(layer "B.Fab")
		)
		(pad "1" smd rect
			(at 0 0 270)
			(size 0.508 0.508)
			(layers "B.Cu" "B.Mask" "B.Paste")
			(net "P3V3_STBY")
		)
		(pad "2" smd rect
			(at 0 0.889 270)
			(size 0.508 0.508)
			(layers "B.Cu" "B.Mask" "B.Paste")
			(net "VR_PVDDQ_GHJ_VDD")
		)
		(zone
			(layer "B.Cu")
			(hatch none 0.5)
			(connect_pads
				(clearance 0)
			)
			(min_thickness 0.25)
			(keepout
				(tracks allowed)
				(vias not_allowed)
				(pads allowed)
				(copperpour not_allowed)
				(footprints allowed)
			)
			(placement
				(enabled no)
				(sheetname "")
			)
			(fill
				(thermal_gap 0.5)
				(thermal_bridge_width 0.5)
				(island_removal_mode 0)
			)
			(polygon
				(pts
					(xy 14.556232 4.791456) (xy 14.556232 4.283456) (xy 14.175232 4.283456) (xy 14.175232 4.791456)
				)
			)
		)
		(zone
			(layer "B.Cu")
			(hatch none 0.5)
			(connect_pads
				(clearance 0)
			)
			(min_thickness 0.25)
			(keepout
				(tracks not_allowed)
				(vias allowed)
				(pads allowed)
				(copperpour not_allowed)
				(footprints allowed)
			)
			(placement
				(enabled no)
				(sheetname "")
			)
			(fill
				(thermal_gap 0.5)
				(thermal_bridge_width 0.5)
				(island_removal_mode 0)
			)
			(polygon
				(pts
					(xy 14.556232 4.791456) (xy 14.556232 4.283456) (xy 14.175232 4.283456) (xy 14.175232 4.791456)
				)
			)
		)
	)
	(footprint ""
		(layer "B.Cu")
		(at 445.2366 -128.7272 180)
		(property "Reference" "U2M1"
			(at -3.48742 -1.08331 0)
			(unlocked yes)
			(layer "B.SilkS")
			(effects
				(font
					(size 0.7874 0.5842)
					(thickness 0.1524)
				)
				(justify left mirror)
			)
		)
		(property "Value" ""
			(at 0 0 0)
			(layer "B.Fab")
			(effects
				(font
					(size 1.27 1.27)
				)
				(justify mirror)
			)
		)
		(duplicate_pad_numbers_are_jumpers no)
		(fp_circle
			(center 0.848614 -0.6477)
			(end 0.721614 -0.6477)
			(stroke
				(width 0.254)
				(type default)
			)
			(fill no)
			(layer "B.SilkS")
		)
		(fp_poly
			(pts
				(xy -0.21463 -0.450088) (xy -1.56337 -0.450088) (xy -1.56337 1.75006) (xy -0.21463 1.75006)
			)
			(stroke
				(width 0)
				(type default)
			)
			(fill no)
			(layer "B.CrtYd")
		)
		(fp_line
			(start -0.21463 1.75006)
			(end -0.21463 -0.450088)
			(stroke
				(width 0.1)
				(type default)
			)
			(layer "B.Fab")
		)
		(fp_line
			(start -0.21463 -0.450088)
			(end -1.56337 -0.450088)
			(stroke
				(width 0.1)
				(type default)
			)
			(layer "B.Fab")
		)
		(fp_line
			(start -1.56337 1.75006)
			(end -0.21463 1.75006)
			(stroke
				(width 0.1)
				(type default)
			)
			(layer "B.Fab")
		)
		(fp_line
			(start -1.56337 -0.450088)
			(end -1.56337 1.75006)
			(stroke
				(width 0.1)
				(type default)
			)
			(layer "B.Fab")
		)
		(fp_circle
			(center 0.848614 -0.6477)
			(end 0.721614 -0.6477)
			(stroke
				(width 0.254)
				(type default)
			)
			(fill no)
			(layer "B.Fab")
		)
		(pad "1" smd rect
			(at 0 0)
			(size 1.016 0.381)
			(layers "B.Cu" "B.Mask" "B.Paste")
			(net "JTAG_MCP_CPU0_TDI")
		)
		(pad "2" smd rect
			(at 0 0.649986)
			(size 1.016 0.381)
			(layers "B.Cu" "B.Mask" "B.Paste")
			(net "GND")
		)
		(pad "3" smd rect
			(at 0 1.299972)
			(size 1.016 0.381)
			(layers "B.Cu" "B.Mask" "B.Paste")
			(net "JTAG_MCP_CPU1_TDI")
		)
		(pad "4" smd rect
			(at -1.778 1.299972)
			(size 1.016 0.381)
			(layers "B.Cu" "B.Mask" "B.Paste")
			(net "JTAG_MCP_MUX_TDI")
		)
		(pad "5" smd rect
			(at -1.778 0.649986)
			(size 1.016 0.381)
			(layers "B.Cu" "B.Mask" "B.Paste")
			(net "P3V3_STBY")
		)
		(pad "6" smd rect
			(at -1.778 0)
			(size 1.016 0.381)
			(layers "B.Cu" "B.Mask" "B.Paste")
			(net "FM_CPU0_CD_PRES")
		)
	)
	(footprint ""
		(layer "B.Cu")
		(at 271.223486 -85.06714)
		(property "Reference" "C5P5"
			(at 0 0 0)
			(layer "B.SilkS")
			(hide yes)
			(effects
				(font
					(size 1.27 1.27)
				)
				(justify mirror)
			)
		)
		(property "Value" ""
			(at 0 0 0)
			(layer "B.Fab")
			(effects
				(font
					(size 1.27 1.27)
				)
				(justify mirror)
			)
		)
		(duplicate_pad_numbers_are_jumpers no)
		(fp_poly
			(pts
				(xy 0.7239 -0.2159) (xy -0.7239 -0.2159) (xy -0.7239 1.9939) (xy 0.7239 1.9939)
			)
			(stroke
				(width 0)
				(type default)
			)
			(fill no)
			(layer "B.CrtYd")
		)
		(fp_line
			(start -0.7239 -0.2159)
			(end 0.7239 -0.2159)
			(stroke
				(width 0.1)
				(type default)
			)
			(layer "B.Fab")
		)
		(fp_line
			(start -0.7239 1.9939)
			(end -0.7239 -0.2159)
			(stroke
				(width 0.1)
				(type default)
			)
			(layer "B.Fab")
		)
		(fp_line
			(start 0.7239 -0.2159)
			(end 0.7239 1.9939)
			(stroke
				(width 0.1)
				(type default)
			)
			(layer "B.Fab")
		)
		(fp_line
			(start 0.7239 1.9939)
			(end -0.7239 1.9939)
			(stroke
				(width 0.1)
				(type default)
			)
			(layer "B.Fab")
		)
		(pad "1" smd rect
			(at 0 0 180)
			(size 1.27 1.016)
			(layers "B.Cu" "B.Mask" "B.Paste")
			(net "PVDDQ_DEF")
		)
		(pad "2" smd rect
			(at 0 1.778 180)
			(size 1.27 1.016)
			(layers "B.Cu" "B.Mask" "B.Paste")
			(net "GND")
		)
		(zone
			(layer "B.Cu")
			(hatch none 0.5)
			(connect_pads
				(clearance 0)
			)
			(min_thickness 0.25)
			(keepout
				(tracks not_allowed)
				(vias allowed)
				(pads allowed)
				(copperpour not_allowed)
				(footprints allowed)
			)
			(placement
				(enabled no)
				(sheetname "")
			)
			(fill
				(thermal_gap 0.5)
				(thermal_bridge_width 0.5)
				(island_removal_mode 0)
			)
			(polygon
				(pts
					(xy 271.858486 -84.55914) (xy 270.588486 -84.55914) (xy 270.588486 -83.79714) (xy 271.858486 -83.79714)
				)
			)
		)
	)
	(footprint ""
		(layer "B.Cu")
		(at 392.6586 -104.6226 135)
		(property "Reference" "C2N19"
			(at 0 0 135)
			(layer "B.SilkS")
			(hide yes)
			(effects
				(font
					(size 1.27 1.27)
				)
				(justify mirror)
			)
		)
		(property "Value" ""
			(at 0 0 135)
			(layer "B.Fab")
			(effects
				(font
					(size 1.27 1.27)
				)
				(justify mirror)
			)
		)
		(duplicate_pad_numbers_are_jumpers no)
		(fp_poly
			(pts
				(xy -0.279514 0.91437) (xy -0.279514 -0.11433) (xy 0.279286 -0.114331) (xy 0.279286 0.91437)
			)
			(stroke
				(width 0)
				(type default)
			)
			(fill no)
			(layer "B.CrtYd")
		)
		(fp_line
			(start 0.279466 -0.114229)
			(end -0.279466 -0.114229)
			(stroke
				(width 0.1)
				(type default)
			)
			(layer "B.Fab")
		)
		(fp_line
			(start -0.279466 -0.114229)
			(end -0.279286 0.91437)
			(stroke
				(width 0.1)
				(type default)
			)
			(layer "B.Fab")
		)
		(fp_line
			(start 0.279286 0.91437)
			(end 0.279466 -0.114229)
			(stroke
				(width 0.1)
				(type default)
			)
			(layer "B.Fab")
		)
		(fp_line
			(start -0.279286 0.91437)
			(end 0.279286 0.91437)
			(stroke
				(width 0.1)
				(type default)
			)
			(layer "B.Fab")
		)
		(pad "1" smd custom
			(at 0 0 45)
			(size 0.10414 0.10414)
			(layers "B.Cu" "B.Mask" "B.Paste")
			(net "P3V3_STBY")
			(options
				(clearance outline)
				(anchor circle)
			)
			(primitives
				(gr_poly
					(pts
						(xy -0.20828 -0.08636) (xy -0.20828 0.08636) (xy -0.08636 0.20828) (xy 0.086614 0.20828) (xy 0.20828 0.086614)
						(xy 0.20828 -0.08636) (xy 0.08636 -0.20828) (xy -0.08636 -0.20828)
					)
					(width 0)
					(fill yes)
				)
			)
		)
		(pad "2" smd custom
			(at 0 0.8001 45)
			(size 0.10414 0.10414)
			(layers "B.Cu" "B.Mask" "B.Paste")
			(net "GND")
			(options
				(clearance outline)
				(anchor circle)
			)
			(primitives
				(gr_poly
					(pts
						(xy -0.20828 -0.08636) (xy -0.20828 0.08636) (xy -0.08636 0.20828) (xy 0.086614 0.20828) (xy 0.20828 0.086614)
						(xy 0.20828 -0.08636) (xy 0.08636 -0.20828) (xy -0.08636 -0.20828)
					)
					(width 0)
					(fill yes)
				)
			)
		)
		(zone
			(layer "B.Cu")
			(hatch none 0.5)
			(connect_pads
				(clearance 0)
			)
			(min_thickness 0.25)
			(keepout
				(tracks allowed)
				(vias not_allowed)
				(pads allowed)
				(copperpour not_allowed)
				(footprints allowed)
			)
			(placement
				(enabled no)
				(sheetname "")
			)
			(fill
				(thermal_gap 0.5)
				(thermal_bridge_width 0.5)
				(island_removal_mode 0)
			)
			(polygon
				(pts
					(xy 392.744706 -104.832658) (xy 393.0142 -105.102152) (xy 393.138152 -104.9782) (xy 392.868912 -104.708706)
				)
			)
		)
		(zone
			(layer "B.Cu")
			(hatch none 0.5)
			(connect_pads
				(clearance 0)
			)
			(min_thickness 0.25)
			(keepout
				(tracks not_allowed)
				(vias allowed)
				(pads allowed)
				(copperpour not_allowed)
				(footprints allowed)
			)
			(placement
				(enabled no)
				(sheetname "")
			)
			(fill
				(thermal_gap 0.5)
				(thermal_bridge_width 0.5)
				(island_removal_mode 0)
			)
			(polygon
				(pts
					(xy 392.744706 -104.832658) (xy 393.0142 -105.102152) (xy 393.138152 -104.9782) (xy 392.868912 -104.708706)
				)
			)
		)
	)
	(footprint ""
		(layer "B.Cu")
		(at 167.005 -15.24 90)
		(property "Reference" "C6U2"
			(at 0 0 90)
			(layer "B.SilkS")
			(hide yes)
			(effects
				(font
					(size 1.27 1.27)
				)
				(justify mirror)
			)
		)
		(property "Value" ""
			(at 0 0 90)
			(layer "B.Fab")
			(effects
				(font
					(size 1.27 1.27)
				)
				(justify mirror)
			)
		)
		(duplicate_pad_numbers_are_jumpers no)
		(fp_rect
			(start -0.7239 -0.2159)
			(end 0.7239 1.9939)
			(stroke
				(width 0)
				(type default)
			)
			(fill no)
			(layer "B.CrtYd")
		)
		(fp_line
			(start 0.7239 -0.2159)
			(end 0.7239 1.9939)
			(stroke
				(width 0.1)
				(type default)
			)
			(layer "B.Fab")
		)
		(fp_line
			(start -0.7239 -0.2159)
			(end 0.7239 -0.2159)
			(stroke
				(width 0.1)
				(type default)
			)
			(layer "B.Fab")
		)
		(fp_line
			(start 0.7239 1.9939)
			(end -0.7239 1.9939)
			(stroke
				(width 0.1)
				(type default)
			)
			(layer "B.Fab")
		)
		(fp_line
			(start -0.7239 1.9939)
			(end -0.7239 -0.2159)
			(stroke
				(width 0.1)
				(type default)
			)
			(layer "B.Fab")
		)
		(pad "1" smd rect
			(at 0 0 270)
			(size 1.27 1.016)
			(layers "B.Cu" "B.Mask" "B.Paste")
			(net "PVPP_GHJ")
		)
		(pad "2" smd rect
			(at 0 1.778 270)
			(size 1.27 1.016)
			(layers "B.Cu" "B.Mask" "B.Paste")
			(net "GND")
		)
		(zone
			(layer "B.Cu")
			(hatch none 0.5)
			(connect_pads
				(clearance 0)
			)
			(min_thickness 0.25)
			(keepout
				(tracks not_allowed)
				(vias allowed)
				(pads allowed)
				(copperpour not_allowed)
				(footprints allowed)
			)
			(placement
				(enabled no)
				(sheetname "")
			)
			(fill
				(thermal_gap 0.5)
				(thermal_bridge_width 0.5)
				(island_removal_mode 0)
			)
			(polygon
				(pts
					(xy 167.513 -14.605) (xy 168.275 -14.605) (xy 168.275 -15.875) (xy 167.513 -15.875)
				)
			)
		)
	)
	(footprint ""
		(layer "B.Cu")
		(at 245.7577 -17.7546 -90)
		(property "Reference" "C5T12"
			(at -1.848866 0.752348 270)
			(unlocked yes)
			(layer "B.SilkS")
			(effects
				(font
					(size 1.27 0.9652)
					(thickness 0.1524)
				)
				(justify mirror)
			)
		)
		(property "Value" ""
			(at 0 0 90)
			(layer "B.Fab")
			(effects
				(font
					(size 1.27 1.27)
				)
				(justify mirror)
			)
		)
		(duplicate_pad_numbers_are_jumpers no)
		(fp_rect
			(start 0.500126 1.598422)
			(end -0.500126 -0.201422)
			(stroke
				(width 0)
				(type default)
			)
			(fill no)
			(layer "B.CrtYd")
		)
		(fp_line
			(start -0.500126 1.598422)
			(end 0.500126 1.598422)
			(stroke
				(width 0.1)
				(type default)
			)
			(layer "B.Fab")
		)
		(fp_line
			(start 0.500126 1.598422)
			(end 0.500126 -0.201422)
			(stroke
				(width 0.1)
				(type default)
			)
			(layer "B.Fab")
		)
		(fp_line
			(start -0.500126 -0.201422)
			(end -0.500126 1.598422)
			(stroke
				(width 0.1)
				(type default)
			)
			(layer "B.Fab")
		)
		(fp_line
			(start 0.500126 -0.201422)
			(end -0.500126 -0.201422)
			(stroke
				(width 0.1)
				(type default)
			)
			(layer "B.Fab")
		)
		(pad "1" smd rect
			(at 0 0 180)
			(size 0.889 0.9906)
			(layers "B.Cu" "B.Mask" "B.Paste")
			(net "PVDDQ_ABC")
		)
		(pad "2" smd rect
			(at 0 1.397 180)
			(size 0.889 0.9906)
			(layers "B.Cu" "B.Mask" "B.Paste")
			(net "GND")
		)
		(zone
			(layer "B.Cu")
			(hatch none 0.5)
			(connect_pads
				(clearance 0)
			)
			(min_thickness 0.25)
			(keepout
				(tracks not_allowed)
				(vias allowed)
				(pads allowed)
				(copperpour not_allowed)
				(footprints allowed)
			)
			(placement
				(enabled no)
				(sheetname "")
			)
			(fill
				(thermal_gap 0.5)
				(thermal_bridge_width 0.5)
				(island_removal_mode 0)
			)
			(polygon
				(pts
					(xy 244.8052 -17.2593) (xy 245.3132 -17.2593) (xy 245.3132 -18.2499) (xy 244.8052 -18.2499)
				)
			)
		)
		(zone
			(layer "B.Cu")
			(hatch none 0.5)
			(connect_pads
				(clearance 0)
			)
			(min_thickness 0.25)
			(keepout
				(tracks allowed)
				(vias not_allowed)
				(pads allowed)
				(copperpour not_allowed)
				(footprints allowed)
			)
			(placement
				(enabled no)
				(sheetname "")
			)
			(fill
				(thermal_gap 0.5)
				(thermal_bridge_width 0.5)
				(island_removal_mode 0)
			)
			(polygon
				(pts
					(xy 244.8052 -17.2593) (xy 245.3132 -17.2593) (xy 245.3132 -18.2499) (xy 244.8052 -18.2499)
				)
			)
		)
	)
	(footprint ""
		(layer "B.Cu")
		(at 253.392432 -8.1534 90)
		(property "Reference" "C5U6"
			(at -1.848866 0.752348 90)
			(unlocked yes)
			(layer "B.SilkS")
			(effects
				(font
					(size 1.27 0.9652)
					(thickness 0.1524)
				)
				(justify mirror)
			)
		)
		(property "Value" ""
			(at 0 0 90)
			(layer "B.Fab")
			(effects
				(font
					(size 1.27 1.27)
				)
				(justify mirror)
			)
		)
		(duplicate_pad_numbers_are_jumpers no)
		(fp_rect
			(start 0.500126 1.598422)
			(end -0.500126 -0.201422)
			(stroke
				(width 0)
				(type default)
			)
			(fill no)
			(layer "B.CrtYd")
		)
		(fp_line
			(start 0.500126 -0.201422)
			(end -0.500126 -0.201422)
			(stroke
				(width 0.1)
				(type default)
			)
			(layer "B.Fab")
		)
		(fp_line
			(start -0.500126 -0.201422)
			(end -0.500126 1.598422)
			(stroke
				(width 0.1)
				(type default)
			)
			(layer "B.Fab")
		)
		(fp_line
			(start 0.500126 1.598422)
			(end 0.500126 -0.201422)
			(stroke
				(width 0.1)
				(type default)
			)
			(layer "B.Fab")
		)
		(fp_line
			(start -0.500126 1.598422)
			(end 0.500126 1.598422)
			(stroke
				(width 0.1)
				(type default)
			)
			(layer "B.Fab")
		)
		(pad "1" smd rect
			(at 0 0)
			(size 0.889 0.9906)
			(layers "B.Cu" "B.Mask" "B.Paste")
			(net "PVDDQ_ABC")
		)
		(pad "2" smd rect
			(at 0 1.397)
			(size 0.889 0.9906)
			(layers "B.Cu" "B.Mask" "B.Paste")
			(net "GND")
		)
		(zone
			(layer "B.Cu")
			(hatch none 0.5)
			(connect_pads
				(clearance 0)
			)
			(min_thickness 0.25)
			(keepout
				(tracks not_allowed)
				(vias allowed)
				(pads allowed)
				(copperpour not_allowed)
				(footprints allowed)
			)
			(placement
				(enabled no)
				(sheetname "")
			)
			(fill
				(thermal_gap 0.5)
				(thermal_bridge_width 0.5)
				(island_removal_mode 0)
			)
			(polygon
				(pts
					(xy 254.344932 -8.6487) (xy 253.836932 -8.6487) (xy 253.836932 -7.6581) (xy 254.344932 -7.6581)
				)
			)
		)
		(zone
			(layer "B.Cu")
			(hatch none 0.5)
			(connect_pads
				(clearance 0)
			)
			(min_thickness 0.25)
			(keepout
				(tracks allowed)
				(vias not_allowed)
				(pads allowed)
				(copperpour not_allowed)
				(footprints allowed)
			)
			(placement
				(enabled no)
				(sheetname "")
			)
			(fill
				(thermal_gap 0.5)
				(thermal_bridge_width 0.5)
				(island_removal_mode 0)
			)
			(polygon
				(pts
					(xy 254.344932 -8.6487) (xy 253.836932 -8.6487) (xy 253.836932 -7.6581) (xy 254.344932 -7.6581)
				)
			)
		)
	)
)
